(kicad_pcb
	(version 20260206)
	(generator "pcbnew")
	(generator_version "10.0")
	(general
		(thickness 1.6)
		(legacy_teardrops no)
	)
	(paper "A4")
	(title_block
		(title "netronome-mezz — pcbd0082-001_rev01_jul9_a.brd")
		(comment 1 "Open CloudServer (Microsoft) / footprints 496-505 of 714")
	)
	(layers
		(0 "F.Cu" signal "TOP")
		(4 "In1.Cu" signal "02_GND")
		(6 "In2.Cu" signal "03_SIG")
		(8 "In3.Cu" signal "04_SIG")
		(10 "In4.Cu" signal "05_GND")
		(12 "In5.Cu" signal "06_PWR1")
		(14 "In6.Cu" signal "07_SIG")
		(16 "In7.Cu" signal "08_SIG")
		(18 "In8.Cu" signal "09_GND")
		(2 "B.Cu" signal "BOTTOM")
		(9 "F.Adhes" user "F.Adhesive")
		(11 "B.Adhes" user "B.Adhesive")
		(13 "F.Paste" user "Package Geometry/Pastemask Top")
		(15 "B.Paste" user "Package Geometry/Pastemask Bottom")
		(5 "F.SilkS" user "Ref Des/Silkscreen Top")
		(7 "B.SilkS" user "Ref Des/Silkscreen Bottom")
		(1 "F.Mask" user "Board Geometry/Soldermask Top")
		(3 "B.Mask" user "Board Geometry/Soldermask Bottom")
		(17 "Dwgs.User" user "User.Drawings")
		(19 "Cmts.User" user "User.Comments")
		(21 "Eco1.User" user "User.Eco1")
		(23 "Eco2.User" user "User.Eco2")
		(25 "Edge.Cuts" user "Board Geometry/Outline")
		(27 "Margin" user)
		(31 "F.CrtYd" user "Package Geometry/Place Bound Top")
		(29 "B.CrtYd" user "Package Geometry/Place Bound Bottom")
		(35 "F.Fab" user "Ref Des/Assembly Top")
		(33 "B.Fab" user "Ref Des/Assembly Bottom")
		(45 "User.4" user "COMPVAL_TYPE_BOTTOM")
	)
	(footprint ""
		(layer "B.Cu")
		(at 63.213996 0.762 180)
		(property "Reference" "C154"
			(at 0.145212 0.8763 270)
			(unlocked yes)
			(layer "B.SilkS")
			(effects
				(font
					(size 0.7874 0.5842)
					(thickness 0.127)
				)
				(justify left mirror)
			)
		)
		(property "Value" "0.22UF"
			(at 0.091846 0.2921 90)
			(unlocked yes)
			(layer "B.Fab")
			(hide yes)
			(effects
				(font
					(size 0.7874 0.5842)
					(thickness 0.2032)
				)
				(justify left mirror)
			)
		)
		(property "Device Type" "CAPC0062"
			(at 0.091846 0.2921 90)
			(unlocked yes)
			(layer "B.Fab")
			(hide yes)
			(effects
				(font
					(size 0.7874 0.5842)
					(thickness 0.2032)
				)
				(justify left mirror)
			)
		)
		(duplicate_pad_numbers_are_jumpers no)
		(fp_poly
			(pts
				(xy -0.635 1.0668) (xy -0.635 -1.0668) (xy 0.635 -1.0668) (xy 0.635 1.0668)
			)
			(stroke
				(width 0)
				(type default)
			)
			(fill no)
			(layer "B.CrtYd")
		)
		(fp_line
			(start 0.254 0.508)
			(end 0.254 -0.508)
			(stroke
				(width 0.0254)
				(type default)
			)
			(layer "B.Fab")
		)
		(fp_line
			(start 0.254 -0.508)
			(end -0.254 -0.508)
			(stroke
				(width 0.0254)
				(type default)
			)
			(layer "B.Fab")
		)
		(fp_line
			(start -0.254 0.508)
			(end 0.254 0.508)
			(stroke
				(width 0.0254)
				(type default)
			)
			(layer "B.Fab")
		)
		(fp_line
			(start -0.254 -0.508)
			(end -0.254 0.508)
			(stroke
				(width 0.0254)
				(type default)
			)
			(layer "B.Fab")
		)
		(pad "1" smd rect
			(at 0 -0.4191)
			(size 0.508 0.5334)
			(layers "B.Cu" "B.Mask" "B.Paste")
			(net "_NFP_PCIE0_PER0_N")
		)
		(pad "2" smd rect
			(at 0 0.4191)
			(size 0.508 0.5334)
			(layers "B.Cu" "B.Mask" "B.Paste")
			(net "NFP_PCIE0_PER0_N")
		)
		(zone
			(layer "B.Cu")
			(hatch none 0.5)
			(connect_pads
				(clearance 0)
			)
			(min_thickness 0.25)
			(keepout
				(tracks not_allowed)
				(vias allowed)
				(pads allowed)
				(copperpour not_allowed)
				(footprints allowed)
			)
			(placement
				(enabled no)
				(sheetname "")
			)
			(fill
				(thermal_gap 0.5)
				(thermal_bridge_width 0.5)
				(island_removal_mode 0)
			)
			(polygon
				(pts
					(xy 63.239396 0.7874) (xy 63.239396 0.7366) (xy 63.188596 0.7366) (xy 63.188596 0.7874)
				)
			)
		)
	)
	(footprint ""
		(layer "B.Cu")
		(at 41.237027 24.541988)
		(property "Reference" "R365"
			(at 0 0 0)
			(layer "B.SilkS")
			(hide yes)
			(effects
				(font
					(size 1.27 1.27)
				)
				(justify mirror)
			)
		)
		(property "Value" ""
			(at 0 0 0)
			(layer "B.Fab")
			(effects
				(font
					(size 1.27 1.27)
				)
				(justify mirror)
			)
		)
		(duplicate_pad_numbers_are_jumpers no)
		(fp_circle
			(center 0 0)
			(end 0.104648 0)
			(stroke
				(width 0.1016)
				(type default)
			)
			(fill no)
			(layer "B.SilkS")
		)
		(fp_poly
			(pts
				(xy 0.381 -0.889) (xy 0.381 0.889) (xy -0.381 0.889) (xy -0.381 -0.889)
			)
			(stroke
				(width 0)
				(type default)
			)
			(fill no)
			(layer "B.CrtYd")
		)
		(fp_line
			(start -0.508 -1.016)
			(end -0.508 1.016)
			(stroke
				(width 0.0254)
				(type default)
			)
			(layer "B.Fab")
		)
		(fp_line
			(start -0.508 1.016)
			(end 0.508 1.016)
			(stroke
				(width 0.0254)
				(type default)
			)
			(layer "B.Fab")
		)
		(fp_line
			(start 0.254 -1.016)
			(end -0.508 -1.016)
			(stroke
				(width 0.0254)
				(type default)
			)
			(layer "B.Fab")
		)
		(fp_line
			(start 0.508 -1.016)
			(end 0.254 -1.016)
			(stroke
				(width 0.0254)
				(type default)
			)
			(layer "B.Fab")
		)
		(fp_line
			(start 0.508 1.016)
			(end 0.508 -1.016)
			(stroke
				(width 0.0254)
				(type default)
			)
			(layer "B.Fab")
		)
		(pad "1" smd custom
			(at 0 -0.500126 180)
			(size 0.127 0.127)
			(layers "B.Cu" "B.Mask" "B.Paste")
			(net "_NFP_PCIE0_RESET_OUT_L")
			(options
				(clearance outline)
				(anchor circle)
			)
			(primitives
				(gr_poly
					(pts
						(xy -0.1778 0.254) (xy 0.1778 0.254) (xy 0.254 0.1778) (xy 0.254 -0.1778) (xy 0.1778 -0.254) (xy -0.1778 -0.254)
						(xy -0.254 -0.1778) (xy -0.254 0.1778)
					)
					(width 0)
					(fill yes)
				)
			)
		)
		(pad "2" smd custom
			(at 0 0.500126 180)
			(size 0.127 0.127)
			(layers "B.Cu" "B.Mask" "B.Paste")
			(net "VDD_3.3V")
			(options
				(clearance outline)
				(anchor circle)
			)
			(primitives
				(gr_poly
					(pts
						(xy -0.1778 0.254) (xy 0.1778 0.254) (xy 0.254 0.1778) (xy 0.254 -0.1778) (xy 0.1778 -0.254) (xy -0.1778 -0.254)
						(xy -0.254 -0.1778) (xy -0.254 0.1778)
					)
					(width 0)
					(fill yes)
				)
			)
		)
	)
	(footprint ""
		(layer "B.Cu")
		(at 40.237029 14.542008)
		(property "Reference" "R46"
			(at 1.011301 0.570992 270)
			(unlocked yes)
			(layer "B.SilkS")
			(effects
				(font
					(size 0.7874 0.5842)
					(thickness 0.127)
				)
				(justify mirror)
			)
		)
		(property "Value" ""
			(at 0 0 0)
			(layer "B.Fab")
			(effects
				(font
					(size 1.27 1.27)
				)
				(justify mirror)
			)
		)
		(duplicate_pad_numbers_are_jumpers no)
		(fp_circle
			(center 0 0)
			(end 0.104648 0)
			(stroke
				(width 0.1016)
				(type default)
			)
			(fill no)
			(layer "B.SilkS")
		)
		(fp_poly
			(pts
				(xy 0.381 -0.889) (xy 0.381 0.889) (xy -0.381 0.889) (xy -0.381 -0.889)
			)
			(stroke
				(width 0)
				(type default)
			)
			(fill no)
			(layer "B.CrtYd")
		)
		(fp_line
			(start -0.508 -1.016)
			(end -0.508 1.016)
			(stroke
				(width 0.0254)
				(type default)
			)
			(layer "B.Fab")
		)
		(fp_line
			(start -0.508 1.016)
			(end 0.508 1.016)
			(stroke
				(width 0.0254)
				(type default)
			)
			(layer "B.Fab")
		)
		(fp_line
			(start 0.254 -1.016)
			(end -0.508 -1.016)
			(stroke
				(width 0.0254)
				(type default)
			)
			(layer "B.Fab")
		)
		(fp_line
			(start 0.508 -1.016)
			(end 0.254 -1.016)
			(stroke
				(width 0.0254)
				(type default)
			)
			(layer "B.Fab")
		)
		(fp_line
			(start 0.508 1.016)
			(end 0.508 -1.016)
			(stroke
				(width 0.0254)
				(type default)
			)
			(layer "B.Fab")
		)
		(pad "1" smd custom
			(at 0 -0.500126 180)
			(size 0.127 0.127)
			(layers "B.Cu" "B.Mask" "B.Paste")
			(net "PGRM_JTAG_TRST_L")
			(options
				(clearance outline)
				(anchor circle)
			)
			(primitives
				(gr_poly
					(pts
						(xy -0.1778 0.254) (xy 0.1778 0.254) (xy 0.254 0.1778) (xy 0.254 -0.1778) (xy 0.1778 -0.254) (xy -0.1778 -0.254)
						(xy -0.254 -0.1778) (xy -0.254 0.1778)
					)
					(width 0)
					(fill yes)
				)
			)
		)
		(pad "2" smd custom
			(at 0 0.500126 180)
			(size 0.127 0.127)
			(layers "B.Cu" "B.Mask" "B.Paste")
			(net "GND")
			(options
				(clearance outline)
				(anchor circle)
			)
			(primitives
				(gr_poly
					(pts
						(xy -0.1778 0.254) (xy 0.1778 0.254) (xy 0.254 0.1778) (xy 0.254 -0.1778) (xy 0.1778 -0.254) (xy -0.1778 -0.254)
						(xy -0.254 -0.1778) (xy -0.254 0.1778)
					)
					(width 0)
					(fill yes)
				)
			)
		)
	)
	(footprint ""
		(layer "B.Cu")
		(at 72.251011 14.256004)
		(property "Reference" "V_A-DQ24"
			(at 0 0 0)
			(layer "B.SilkS")
			(hide yes)
			(effects
				(font
					(size 1.27 1.27)
				)
				(justify mirror)
			)
		)
		(property "Value" ""
			(at 0 0 0)
			(layer "B.Fab")
			(effects
				(font
					(size 1.27 1.27)
				)
				(justify mirror)
			)
		)
		(duplicate_pad_numbers_are_jumpers no)
		(pad "1" thru_hole circle
			(at 0 0 180)
			(size 0.4572 0.4572)
			(drill 0.20574)
			(layers "*.Cu" "*.Mask")
			(remove_unused_layers no)
			(net "DDR0_32A_DQ24")
			(clearance 0.1143)
			(thermal_gap 0.1143)
		)
	)
	(footprint ""
		(layer "B.Cu")
		(at 22.352 2.794)
		(property "Reference" "R380"
			(at -1.04267 0.889 270)
			(unlocked yes)
			(layer "B.SilkS")
			(effects
				(font
					(size 0.7874 0.5842)
					(thickness 0.127)
				)
				(justify left mirror)
			)
		)
		(property "Value" "4.75K"
			(at 0.148158 1.3462 270)
			(unlocked yes)
			(layer "B.Fab")
			(hide yes)
			(effects
				(font
					(size 1.27 0.9652)
					(thickness 0.000001)
				)
				(justify left mirror)
			)
		)
		(property "Device Type" "REST4024"
			(at 0.148158 1.3462 270)
			(unlocked yes)
			(layer "B.Fab")
			(hide yes)
			(effects
				(font
					(size 1.27 0.9652)
					(thickness 0.000001)
				)
				(justify left mirror)
			)
		)
		(duplicate_pad_numbers_are_jumpers no)
		(fp_poly
			(pts
				(xy -0.635 1.0668) (xy -0.635 -1.0668) (xy 0.635 -1.0668) (xy 0.635 1.0668)
			)
			(stroke
				(width 0)
				(type default)
			)
			(fill no)
			(layer "B.CrtYd")
		)
		(fp_line
			(start -0.254 -0.508)
			(end -0.254 0.508)
			(stroke
				(width 0.0254)
				(type default)
			)
			(layer "B.Fab")
		)
		(fp_line
			(start -0.254 0.508)
			(end 0.254 0.508)
			(stroke
				(width 0.0254)
				(type default)
			)
			(layer "B.Fab")
		)
		(fp_line
			(start 0.254 -0.508)
			(end -0.254 -0.508)
			(stroke
				(width 0.0254)
				(type default)
			)
			(layer "B.Fab")
		)
		(fp_line
			(start 0.254 0.508)
			(end 0.254 -0.508)
			(stroke
				(width 0.0254)
				(type default)
			)
			(layer "B.Fab")
		)
		(pad "1" smd rect
			(at 0 -0.4191 180)
			(size 0.508 0.5334)
			(layers "B.Cu" "B.Mask" "B.Paste")
			(net "NFP_PCIE0_WAKE_L")
		)
		(pad "2" smd rect
			(at 0 0.4191 180)
			(size 0.508 0.5334)
			(layers "B.Cu" "B.Mask" "B.Paste")
			(net "EXT_3.3V")
		)
		(zone
			(layer "B.Cu")
			(hatch none 0.5)
			(connect_pads
				(clearance 0)
			)
			(min_thickness 0.25)
			(keepout
				(tracks not_allowed)
				(vias allowed)
				(pads allowed)
				(copperpour not_allowed)
				(footprints allowed)
			)
			(placement
				(enabled no)
				(sheetname "")
			)
			(fill
				(thermal_gap 0.5)
				(thermal_bridge_width 0.5)
				(island_removal_mode 0)
			)
			(polygon
				(pts
					(xy 22.3266 2.7686) (xy 22.3266 2.8194) (xy 22.3774 2.8194) (xy 22.3774 2.7686)
				)
			)
		)
	)
	(footprint ""
		(layer "B.Cu")
		(at 72.251011 3.499002)
		(property "Reference" "V_A-DQ14"
			(at 0 0 0)
			(layer "B.SilkS")
			(hide yes)
			(effects
				(font
					(size 1.27 1.27)
				)
				(justify mirror)
			)
		)
		(property "Value" ""
			(at 0 0 0)
			(layer "B.Fab")
			(effects
				(font
					(size 1.27 1.27)
				)
				(justify mirror)
			)
		)
		(duplicate_pad_numbers_are_jumpers no)
		(pad "1" thru_hole circle
			(at 0 0 180)
			(size 0.4572 0.4572)
			(drill 0.20574)
			(layers "*.Cu" "*.Mask")
			(remove_unused_layers no)
			(net "DDR0_32A_DQ14")
			(clearance 0.1143)
			(thermal_gap 0.1143)
		)
	)
	(footprint ""
		(layer "B.Cu")
		(at 45.737018 17.042003 90)
		(property "Reference" "C269"
			(at 0 0 90)
			(layer "B.SilkS")
			(hide yes)
			(effects
				(font
					(size 1.27 1.27)
				)
				(justify mirror)
			)
		)
		(property "Value" ""
			(at 0 0 90)
			(layer "B.Fab")
			(effects
				(font
					(size 1.27 1.27)
				)
				(justify mirror)
			)
		)
		(duplicate_pad_numbers_are_jumpers no)
		(fp_circle
			(center 0 0)
			(end 0 0.104648)
			(stroke
				(width 0.1016)
				(type default)
			)
			(fill no)
			(layer "B.SilkS")
		)
		(fp_poly
			(pts
				(xy 0.381 -0.889) (xy 0.381 0.889) (xy -0.381 0.889) (xy -0.381 -0.889)
			)
			(stroke
				(width 0)
				(type default)
			)
			(fill no)
			(layer "B.CrtYd")
		)
		(fp_line
			(start 0.508 -1.016)
			(end 0.254 -1.016)
			(stroke
				(width 0.0254)
				(type default)
			)
			(layer "B.Fab")
		)
		(fp_line
			(start 0.254 -1.016)
			(end -0.508 -1.016)
			(stroke
				(width 0.0254)
				(type default)
			)
			(layer "B.Fab")
		)
		(fp_line
			(start -0.508 -1.016)
			(end -0.508 1.016)
			(stroke
				(width 0.0254)
				(type default)
			)
			(layer "B.Fab")
		)
		(fp_line
			(start 0.508 1.016)
			(end 0.508 -1.016)
			(stroke
				(width 0.0254)
				(type default)
			)
			(layer "B.Fab")
		)
		(fp_line
			(start -0.508 1.016)
			(end 0.508 1.016)
			(stroke
				(width 0.0254)
				(type default)
			)
			(layer "B.Fab")
		)
		(pad "1" smd custom
			(at 0 -0.500126 270)
			(size 0.127 0.127)
			(layers "B.Cu" "B.Mask" "B.Paste")
			(net "VDD_1.8V")
			(options
				(clearance outline)
				(anchor circle)
			)
			(primitives
				(gr_poly
					(pts
						(xy -0.1778 0.254) (xy 0.1778 0.254) (xy 0.254 0.1778) (xy 0.254 -0.1778) (xy 0.1778 -0.254) (xy -0.1778 -0.254)
						(xy -0.254 -0.1778) (xy -0.254 0.1778)
					)
					(width 0)
					(fill yes)
				)
			)
		)
		(pad "2" smd custom
			(at 0 0.500126 270)
			(size 0.127 0.127)
			(layers "B.Cu" "B.Mask" "B.Paste")
			(net "GND")
			(options
				(clearance outline)
				(anchor circle)
			)
			(primitives
				(gr_poly
					(pts
						(xy -0.1778 0.254) (xy 0.1778 0.254) (xy 0.254 0.1778) (xy 0.254 -0.1778) (xy 0.1778 -0.254) (xy -0.1778 -0.254)
						(xy -0.254 -0.1778) (xy -0.254 0.1778)
					)
					(width 0)
					(fill yes)
				)
			)
		)
	)
	(footprint ""
		(layer "B.Cu")
		(at 82.65099 19.055994)
		(property "Reference" "V2_A-A04"
			(at 0 0 0)
			(layer "B.SilkS")
			(hide yes)
			(effects
				(font
					(size 1.27 1.27)
				)
				(justify mirror)
			)
		)
		(property "Value" ""
			(at 0 0 0)
			(layer "B.Fab")
			(effects
				(font
					(size 1.27 1.27)
				)
				(justify mirror)
			)
		)
		(duplicate_pad_numbers_are_jumpers no)
		(pad "1" thru_hole circle
			(at 0 0 180)
			(size 0.4572 0.4572)
			(drill 0.20574)
			(layers "*.Cu" "*.Mask")
			(remove_unused_layers no)
			(net "DDR0_32A_A4")
			(clearance 0.1143)
			(thermal_gap 0.1143)
		)
	)
	(footprint ""
		(layer "B.Cu")
		(at 44.73702 16.042005 90)
		(property "Reference" "C268"
			(at 0 0 90)
			(layer "B.SilkS")
			(hide yes)
			(effects
				(font
					(size 1.27 1.27)
				)
				(justify mirror)
			)
		)
		(property "Value" ""
			(at 0 0 90)
			(layer "B.Fab")
			(effects
				(font
					(size 1.27 1.27)
				)
				(justify mirror)
			)
		)
		(duplicate_pad_numbers_are_jumpers no)
		(fp_circle
			(center 0 0)
			(end 0 0.104648)
			(stroke
				(width 0.1016)
				(type default)
			)
			(fill no)
			(layer "B.SilkS")
		)
		(fp_poly
			(pts
				(xy 0.381 -0.889) (xy 0.381 0.889) (xy -0.381 0.889) (xy -0.381 -0.889)
			)
			(stroke
				(width 0)
				(type default)
			)
			(fill no)
			(layer "B.CrtYd")
		)
		(fp_line
			(start 0.508 -1.016)
			(end 0.254 -1.016)
			(stroke
				(width 0.0254)
				(type default)
			)
			(layer "B.Fab")
		)
		(fp_line
			(start 0.254 -1.016)
			(end -0.508 -1.016)
			(stroke
				(width 0.0254)
				(type default)
			)
			(layer "B.Fab")
		)
		(fp_line
			(start -0.508 -1.016)
			(end -0.508 1.016)
			(stroke
				(width 0.0254)
				(type default)
			)
			(layer "B.Fab")
		)
		(fp_line
			(start 0.508 1.016)
			(end 0.508 -1.016)
			(stroke
				(width 0.0254)
				(type default)
			)
			(layer "B.Fab")
		)
		(fp_line
			(start -0.508 1.016)
			(end 0.508 1.016)
			(stroke
				(width 0.0254)
				(type default)
			)
			(layer "B.Fab")
		)
		(pad "1" smd custom
			(at 0 -0.500126 270)
			(size 0.127 0.127)
			(layers "B.Cu" "B.Mask" "B.Paste")
			(net "VDD_3.3V")
			(options
				(clearance outline)
				(anchor circle)
			)
			(primitives
				(gr_poly
					(pts
						(xy -0.1778 0.254) (xy 0.1778 0.254) (xy 0.254 0.1778) (xy 0.254 -0.1778) (xy 0.1778 -0.254) (xy -0.1778 -0.254)
						(xy -0.254 -0.1778) (xy -0.254 0.1778)
					)
					(width 0)
					(fill yes)
				)
			)
		)
		(pad "2" smd custom
			(at 0 0.500126 270)
			(size 0.127 0.127)
			(layers "B.Cu" "B.Mask" "B.Paste")
			(net "GND")
			(options
				(clearance outline)
				(anchor circle)
			)
			(primitives
				(gr_poly
					(pts
						(xy -0.1778 0.254) (xy 0.1778 0.254) (xy 0.254 0.1778) (xy 0.254 -0.1778) (xy 0.1778 -0.254) (xy -0.1778 -0.254)
						(xy -0.254 -0.1778) (xy -0.254 0.1778)
					)
					(width 0)
					(fill yes)
				)
			)
		)
	)
	(footprint ""
		(layer "B.Cu")
		(at 56.736996 11.042015 -90)
		(property "Reference" "C78"
			(at 0 0 90)
			(layer "B.SilkS")
			(hide yes)
			(effects
				(font
					(size 1.27 1.27)
				)
				(justify mirror)
			)
		)
		(property "Value" ""
			(at 0 0 90)
			(layer "B.Fab")
			(effects
				(font
					(size 1.27 1.27)
				)
				(justify mirror)
			)
		)
		(duplicate_pad_numbers_are_jumpers no)
		(fp_circle
			(center 0 0)
			(end 0 -0.104648)
			(stroke
				(width 0.1016)
				(type default)
			)
			(fill no)
			(layer "B.SilkS")
		)
		(fp_poly
			(pts
				(xy 0.381 -0.889) (xy 0.381 0.889) (xy -0.381 0.889) (xy -0.381 -0.889)
			)
			(stroke
				(width 0)
				(type default)
			)
			(fill no)
			(layer "B.CrtYd")
		)
		(fp_line
			(start -0.508 1.016)
			(end 0.508 1.016)
			(stroke
				(width 0.0254)
				(type default)
			)
			(layer "B.Fab")
		)
		(fp_line
			(start 0.508 1.016)
			(end 0.508 -1.016)
			(stroke
				(width 0.0254)
				(type default)
			)
			(layer "B.Fab")
		)
		(fp_line
			(start -0.508 -1.016)
			(end -0.508 1.016)
			(stroke
				(width 0.0254)
				(type default)
			)
			(layer "B.Fab")
		)
		(fp_line
			(start 0.254 -1.016)
			(end -0.508 -1.016)
			(stroke
				(width 0.0254)
				(type default)
			)
			(layer "B.Fab")
		)
		(fp_line
			(start 0.508 -1.016)
			(end 0.254 -1.016)
			(stroke
				(width 0.0254)
				(type default)
			)
			(layer "B.Fab")
		)
		(pad "1" smd custom
			(at 0 -0.500126 90)
			(size 0.127 0.127)
			(layers "B.Cu" "B.Mask" "B.Paste")
			(net "VDD_CORE")
			(options
				(clearance outline)
				(anchor circle)
			)
			(primitives
				(gr_poly
					(pts
						(xy -0.1778 0.254) (xy 0.1778 0.254) (xy 0.254 0.1778) (xy 0.254 -0.1778) (xy 0.1778 -0.254) (xy -0.1778 -0.254)
						(xy -0.254 -0.1778) (xy -0.254 0.1778)
					)
					(width 0)
					(fill yes)
				)
			)
		)
		(pad "2" smd custom
			(at 0 0.500126 90)
			(size 0.127 0.127)
			(layers "B.Cu" "B.Mask" "B.Paste")
			(net "GND")
			(options
				(clearance outline)
				(anchor circle)
			)
			(primitives
				(gr_poly
					(pts
						(xy -0.1778 0.254) (xy 0.1778 0.254) (xy 0.254 0.1778) (xy 0.254 -0.1778) (xy 0.1778 -0.254) (xy -0.1778 -0.254)
						(xy -0.254 -0.1778) (xy -0.254 0.1778)
					)
					(width 0)
					(fill yes)
				)
			)
		)
	)
)
